# ZAIUS-MB-PVT-X04-BOM_X31_20180131_Final.xls.xlsx — Component Qual Tracker (bom)
|  |  |  |  |  |  |  |  | Part to be included on following build: |  |  |  |  |  |
| Item No. | Part Group | Single/Sole/Multi | Item Description | ODM P/N | Customer PN | Vendor | Vendor P/N | X00 Build | X01 Build | X02 Build | Qual Build | Qualification Target Date | Qualification Complete Date |
|  | VR Controllers |  |  |  |  | Vendor #1 |  |  |  |  |  |  |  |
|  |  |  |  |  |  | Vendor #2 |  |  |  |  |  |  |  |
|  | FETS |  |  |  |  | Vendor #1 |  |  |  |  |  |  |  |
|  |  |  |  |  |  | Vendor #2 |  |  |  |  |  |  |  |
|  | INDUCTORS |  |  |  |  | Vendor #1 |  |  |  |  |  |  |  |
|  |  |  |  |  |  | Vendor #2 |  |  |  |  |  |  |  |
|  | VREG CAPS |  |  |  |  | Vendor #1 |  |  |  |  |  |  |  |
|  |  |  |  |  |  | Vendor #2 |  |  |  |  |  |  |  |
|  | CRYSTALS |  |  |  |  | Vendor #1 |  |  |  |  |  |  |  |
|  |  |  |  |  |  | Vendor #2 |  |  |  |  |  |  |  |
|  | CONNECTORS |  |  |  |  | Vendor #1 |  |  |  |  |  |  |  |
|  |  |  |  |  |  | Vendor #2 |  |  |  |  |  |  |  |
|  | IC'S |  |  |  |  | Vendor #1 |  |  |  |  |  |  |  |
|  |  |  |  |  |  | Vendor #2 |  |  |  |  |  |  |  |
|  | MISC. |  |  |  |  | Vendor #1 |  |  |  |  |  |  |  |
|  | (HEATSINKS) |  |  |  |  | Vendor #2 |  |  |  |  |  |  |  |
